# TIMECARD (Time Appliance Project (Time Card)) — schematic netlist excerpt (pin names and nets, part order shuffled) for the footprints in the layout excerpt that follows; sources: Cadence DE-HDL packaged netlist, KiCad conversion of R4006-B0001-02_R01.brd

R455  RESISTOR  1MOHM 1%  pkg SMC_0402R_H016  page 24 : \1\ = UNNAMED_524_CAPACITOR_I7_2 ; \2\ = UNNAMED_524_CAPACITOR_I10_2
TP194  TP_PIONT  pkg TP010CT020B030_PTH  page 25 : \1\ = IO_L21N_35

(kicad_pcb
	(version 20260206)
	(generator "pcbnew")
	(generator_version "10.0")
	(general
		(thickness 1.6)
		(legacy_teardrops no)
	)
	(paper "A4")
	(title_block
		(title "timecard-production-celestica-r4006 — R4006-B0001-02_R01.brd")
		(comment 1 "Time Appliance Project (Time Card) / footprints 185-186 of 1113")
	)
	(layers
		(0 "F.Cu" signal "TOP")
		(4 "In1.Cu" signal "L02_GND1")
		(6 "In2.Cu" signal "L03_SIG1")
		(8 "In3.Cu" signal "L04_GND2")
		(10 "In4.Cu" signal "L05_VCC1")
		(12 "In5.Cu" signal "L06_VCC2")
		(14 "In6.Cu" signal "L07_GND3")
		(16 "In7.Cu" signal "L08_SIG2")
		(18 "In8.Cu" signal "L09_GND4")
		(2 "B.Cu" signal "BOTTOM")
		(9 "F.Adhes" user "F.Adhesive")
		(11 "B.Adhes" user "B.Adhesive")
		(13 "F.Paste" user "Package Geometry/Pastemask Top")
		(15 "B.Paste" user "Package Geometry/Pastemask Bottom")
		(5 "F.SilkS" user "Ref Des/Silkscreen Top")
		(7 "B.SilkS" user "Ref Des/Silkscreen Bottom")
		(1 "F.Mask" user "Board Geometry/Soldermask Top")
		(3 "B.Mask" user "Board Geometry/Soldermask Bottom")
		(17 "Dwgs.User" user "User.Drawings")
		(19 "Cmts.User" user "User.Comments")
		(21 "Eco1.User" user "User.Eco1")
		(23 "Eco2.User" user "User.Eco2")
		(25 "Edge.Cuts" user "Board Geometry/Outline")
		(27 "Margin" user)
		(31 "F.CrtYd" user "Package Geometry/Place Bound Top")
		(29 "B.CrtYd" user "Package Geometry/Place Bound Bottom")
		(35 "F.Fab" user "Ref Des/Assembly Top")
		(33 "B.Fab" user "Ref Des/Assembly Bottom")
	)
	(footprint ""
		(layer "F.Cu")
		(at 31.75 -95.25 180)
		(property "Reference" "R455"
			(at -2.667 -1.69037 0)
			(unlocked yes)
			(layer "F.SilkS")
			(effects
				(font
					(size 0.7874 0.5842)
					(thickness 0.1524)
				)
			)
		)
		(property "Value" "VAL*"
			(at 0.02032 2.13233 180)
			(unlocked yes)
			(layer "F.Fab")
			(hide yes)
			(effects
				(font
					(size 0.7874 0.5842)
					(thickness 0.1524)
				)
			)
		)
		(property "Tolerance" "TOL*"
			(at 0.044704 3.05435 180)
			(unlocked yes)
			(layer "Cmts.User")
			(hide yes)
			(effects
				(font
					(size 0.7874 0.5842)
					(thickness 0.1524)
				)
			)
		)
		(property "User Part Number" "PARTNUM*"
			(at 0.02032 4.024884 180)
			(unlocked yes)
			(layer "Cmts.User")
			(hide yes)
			(effects
				(font
					(size 0.7874 0.5842)
					(thickness 0.1524)
				)
			)
		)
		(property "Device Type" "RESISTOR-G155-11004-01,1MOHM,1%"
			(at 0.008382 1.210564 180)
			(unlocked yes)
			(layer "F.Fab")
			(hide yes)
			(effects
				(font
					(size 0.7874 0.5842)
					(thickness 0.1524)
				)
			)
		)
		(duplicate_pad_numbers_are_jumpers no)
		(fp_line
			(start 1.143 0.5588)
			(end 1.143 -0.5588)
			(stroke
				(width 0.1)
				(type default)
			)
			(layer "F.SilkS")
		)
		(fp_line
			(start 1.143 -0.5588)
			(end -1.143 -0.5588)
			(stroke
				(width 0.1)
				(type default)
			)
			(layer "F.SilkS")
		)
		(fp_line
			(start -1.143 0.5588)
			(end 1.143 0.5588)
			(stroke
				(width 0.1)
				(type default)
			)
			(layer "F.SilkS")
		)
		(fp_line
			(start -1.143 -0.5588)
			(end -1.143 0.5588)
			(stroke
				(width 0.1)
				(type default)
			)
			(layer "F.SilkS")
		)
		(fp_poly
			(pts
				(xy -1.143 0.5588) (xy 1.143 0.5588) (xy 1.143 -0.5588) (xy -1.143 -0.5588)
			)
			(stroke
				(width 0)
				(type default)
			)
			(fill no)
			(layer "F.CrtYd")
		)
		(fp_line
			(start 0.508 0.3048)
			(end 0.508 -0.3048)
			(stroke
				(width 0.1)
				(type default)
			)
			(layer "F.Fab")
		)
		(fp_line
			(start 0.508 -0.3048)
			(end -0.508 -0.3048)
			(stroke
				(width 0.1)
				(type default)
			)
			(layer "F.Fab")
		)
		(fp_line
			(start -0.508 0.3048)
			(end 0.508 0.3048)
			(stroke
				(width 0.1)
				(type default)
			)
			(layer "F.Fab")
		)
		(fp_line
			(start -0.508 -0.3048)
			(end -0.508 0.3048)
			(stroke
				(width 0.1)
				(type default)
			)
			(layer "F.Fab")
		)
		(pad "1" smd rect
			(at -0.5334 0 180)
			(size 0.7112 0.6096)
			(layers "F.Cu" "F.Mask" "F.Paste")
			(net "UNNAMED_524_CAPACITOR_I7_2")
		)
		(pad "2" smd rect
			(at 0.5334 0 180)
			(size 0.7112 0.6096)
			(layers "F.Cu" "F.Mask" "F.Paste")
			(net "UNNAMED_524_CAPACITOR_I10_2")
		)
		(zone
			(layer "F.Cu")
			(hatch none 0.5)
			(connect_pads
				(clearance 0)
			)
			(min_thickness 0.25)
			(keepout
				(tracks allowed)
				(vias not_allowed)
				(pads allowed)
				(copperpour not_allowed)
				(footprints allowed)
			)
			(placement
				(enabled no)
				(sheetname "")
			)
			(fill
				(thermal_gap 0.5)
				(thermal_bridge_width 0.5)
				(island_removal_mode 0)
			)
			(polygon
				(pts
					(xy 31.8262 -95.5548) (xy 31.6738 -95.5548) (xy 31.6738 -94.9452) (xy 31.8262 -94.9452)
				)
			)
		)
		(zone
			(layer "F.Cu")
			(hatch none 0.5)
			(connect_pads
				(clearance 0)
			)
			(min_thickness 0.25)
			(keepout
				(tracks not_allowed)
				(vias allowed)
				(pads allowed)
				(copperpour not_allowed)
				(footprints allowed)
			)
			(placement
				(enabled no)
				(sheetname "")
			)
			(fill
				(thermal_gap 0.5)
				(thermal_bridge_width 0.5)
				(island_removal_mode 0)
			)
			(polygon
				(pts
					(xy 31.8262 -95.5548) (xy 31.6738 -95.5548) (xy 31.6738 -94.9452) (xy 31.8262 -94.9452)
				)
			)
		)
	)
	(footprint ""
		(layer "F.Cu")
		(at 122.6312 -28.0162 90)
		(property "Reference" "TP194"
			(at -1.37795 -0.635 0)
			(unlocked yes)
			(layer "F.SilkS")
			(effects
				(font
					(size 0.635 0.4064)
					(thickness 0.1524)
				)
				(justify left)
			)
		)
		(property "Value" ""
			(at 0 0 90)
			(layer "F.Fab")
			(effects
				(font
					(size 1.27 1.27)
				)
			)
		)
		(property "Device Type" "TP_PIONT-TP010CT020B030_PTH-TPA"
			(at -1.341882 0.996696 90)
			(unlocked yes)
			(layer "F.Fab")
			(hide yes)
			(effects
				(font
					(size 0.7874 0.5842)
					(thickness 0.1524)
				)
				(justify left)
			)
		)
		(duplicate_pad_numbers_are_jumpers no)
		(fp_poly
			(pts
				(arc
					(start 0 0.889)
					(mid 0 -0.889)
					(end 0 0.889)
				)
			)
			(stroke
				(width 0)
				(type default)
			)
			(fill no)
			(layer "B.CrtYd")
		)
		(fp_poly
			(pts
				(arc
					(start 0 0.889)
					(mid 0 -0.889)
					(end 0 0.889)
				)
			)
			(stroke
				(width 0)
				(type default)
			)
			(fill no)
			(layer "F.CrtYd")
		)
		(pad "1" thru_hole circle
			(at 0 0 90)
			(size 0.508 0.508)
			(drill 0.254)
			(layers "*.Cu" "*.Mask")
			(remove_unused_layers no)
			(net "IO_L21N_35")
			(clearance 0.1016)
			(padstack
				(mode front_inner_back)
				(layer "Inner"
					(shape circle)
					(size 0.508 0.508)
					(clearance 0.1016)
				)
				(layer "B.Cu"
					(shape circle)
					(size 0.762 0.762)
					(clearance -0.0254)
				)
			)
		)
	)
)
